(kicad_pcb
	(version 20260206)
	(generator "pcbnew")
	(generator_version "10.0")
	(general
		(thickness 1.6)
		(legacy_teardrops no)
	)
	(paper "A4")
	(title_block
		(title "01162023_DA0F0TEBIF0_F0T_Expander_BD_F_brd_V02_OCP.brd")
		(comment 1 "Grand Teton / footprints 7728-7736 of 9728")
	)
	(layers
		(0 "F.Cu" signal "TOP")
		(4 "In1.Cu" signal "GND")
		(6 "In2.Cu" signal "VCC")
		(8 "In3.Cu" signal "VCC1")
		(10 "In4.Cu" signal "GND1")
		(12 "In5.Cu" signal "IN1")
		(14 "In6.Cu" signal "GND2")
		(16 "In7.Cu" signal "IN2")
		(18 "In8.Cu" signal "GND3")
		(20 "In9.Cu" signal "IN3")
		(22 "In10.Cu" signal "GND4")
		(24 "In11.Cu" signal "IN4")
		(26 "In12.Cu" signal "GND5")
		(28 "In13.Cu" signal "IN5")
		(30 "In14.Cu" signal "GND6")
		(32 "In15.Cu" signal "IN6")
		(34 "In16.Cu" signal "GND7")
		(2 "B.Cu" signal "BOTTOM")
		(9 "F.Adhes" user "F.Adhesive")
		(11 "B.Adhes" user "B.Adhesive")
		(13 "F.Paste" user "Package Geometry/Pastemask Top")
		(15 "B.Paste" user "Package Geometry/Pastemask Bottom")
		(5 "F.SilkS" user "Ref Des/Silkscreen Top")
		(7 "B.SilkS" user "Ref Des/Silkscreen Bottom")
		(1 "F.Mask" user "Board Geometry/Soldermask Top")
		(3 "B.Mask" user "Board Geometry/Soldermask Bottom")
		(17 "Dwgs.User" user "User.Drawings")
		(19 "Cmts.User" user "User.Comments")
		(21 "Eco1.User" user "User.Eco1")
		(23 "Eco2.User" user "User.Eco2")
		(25 "Edge.Cuts" user "Board Geometry/Outline")
		(27 "Margin" user)
		(31 "F.CrtYd" user "Package Geometry/Place Bound Top")
		(29 "B.CrtYd" user "Package Geometry/Place Bound Bottom")
		(35 "F.Fab" user "Ref Des/Assembly Top")
		(33 "B.Fab" user "Ref Des/Assembly Bottom")
	)
	(footprint ""
		(layer "B.Cu")
		(at 140.774166 -222.299276 180)
		(property "Reference" "C2308"
			(at 0 0 0)
			(layer "B.SilkS")
			(hide yes)
			(effects
				(font
					(size 1.27 1.27)
				)
				(justify mirror)
			)
		)
		(property "Value" ""
			(at 0 0 0)
			(layer "B.Fab")
			(effects
				(font
					(size 1.27 1.27)
				)
				(justify mirror)
			)
		)
		(duplicate_pad_numbers_are_jumpers no)
		(fp_line
			(start 0.7874 0.4064)
			(end 0.7874 -0.4064)
			(stroke
				(width 0.1524)
				(type default)
			)
			(layer "B.SilkS")
		)
		(fp_line
			(start 0.7874 -0.4064)
			(end -0.7874 -0.4064)
			(stroke
				(width 0.1524)
				(type default)
			)
			(layer "B.SilkS")
		)
		(fp_line
			(start -0.7874 0.4064)
			(end 0.7874 0.4064)
			(stroke
				(width 0.1524)
				(type default)
			)
			(layer "B.SilkS")
		)
		(fp_line
			(start -0.7874 -0.4064)
			(end -0.7874 0.4064)
			(stroke
				(width 0.1524)
				(type default)
			)
			(layer "B.SilkS")
		)
		(fp_line
			(start 0.67945 0.3048)
			(end 0.67945 -0.305054)
			(stroke
				(width 0.1)
				(type default)
			)
			(layer "B.Fab")
		)
		(fp_line
			(start 0.67945 -0.305054)
			(end 0.12065 -0.305054)
			(stroke
				(width 0.1)
				(type default)
			)
			(layer "B.Fab")
		)
		(fp_line
			(start 0.12065 0.3048)
			(end 0.67945 0.3048)
			(stroke
				(width 0.1)
				(type default)
			)
			(layer "B.Fab")
		)
		(fp_line
			(start 0.12065 0.2794)
			(end 0.12065 0.3048)
			(stroke
				(width 0.1)
				(type default)
			)
			(layer "B.Fab")
		)
		(fp_line
			(start 0.12065 -0.2794)
			(end -0.12065 -0.2794)
			(stroke
				(width 0.1)
				(type default)
			)
			(layer "B.Fab")
		)
		(fp_line
			(start 0.12065 -0.305054)
			(end 0.12065 -0.2794)
			(stroke
				(width 0.1)
				(type default)
			)
			(layer "B.Fab")
		)
		(fp_line
			(start -0.120396 0.3048)
			(end -0.120396 0.2794)
			(stroke
				(width 0.1)
				(type default)
			)
			(layer "B.Fab")
		)
		(fp_line
			(start -0.120396 0.2794)
			(end 0.12065 0.2794)
			(stroke
				(width 0.1)
				(type default)
			)
			(layer "B.Fab")
		)
		(fp_line
			(start -0.12065 -0.2794)
			(end -0.12065 -0.3048)
			(stroke
				(width 0.1)
				(type default)
			)
			(layer "B.Fab")
		)
		(fp_line
			(start -0.12065 -0.3048)
			(end -0.67945 -0.3048)
			(stroke
				(width 0.1)
				(type default)
			)
			(layer "B.Fab")
		)
		(fp_line
			(start -0.67945 0.3048)
			(end -0.120396 0.3048)
			(stroke
				(width 0.1)
				(type default)
			)
			(layer "B.Fab")
		)
		(fp_line
			(start -0.67945 -0.3048)
			(end -0.67945 0.3048)
			(stroke
				(width 0.1)
				(type default)
			)
			(layer "B.Fab")
		)
		(pad "1" smd circle
			(at 0.40005 0)
			(size 0 0)
			(layers "B.Cu" "B.Mask" "B.Paste")
			(net "GND")
		)
		(pad "2" smd circle
			(at -0.40005 0)
			(size 0 0)
			(layers "B.Cu" "B.Mask" "B.Paste")
			(net "P1V8_PEX")
		)
	)
	(footprint ""
		(layer "B.Cu")
		(at 57.749948 -292.099746 90)
		(property "Reference" "C1200"
			(at 0 0 90)
			(layer "B.SilkS")
			(hide yes)
			(effects
				(font
					(size 1.27 1.27)
				)
				(justify mirror)
			)
		)
		(property "Value" ""
			(at 0 0 90)
			(layer "B.Fab")
			(effects
				(font
					(size 1.27 1.27)
				)
				(justify mirror)
			)
		)
		(duplicate_pad_numbers_are_jumpers no)
		(fp_line
			(start 0.299974 -0.150114)
			(end -0.299974 -0.150114)
			(stroke
				(width 0.1)
				(type default)
			)
			(layer "B.Fab")
		)
		(fp_line
			(start -0.299974 -0.150114)
			(end -0.299974 0.150114)
			(stroke
				(width 0.1)
				(type default)
			)
			(layer "B.Fab")
		)
		(fp_line
			(start 0.299974 0.150114)
			(end 0.299974 -0.150114)
			(stroke
				(width 0.1)
				(type default)
			)
			(layer "B.Fab")
		)
		(fp_line
			(start -0.299974 0.150114)
			(end 0.299974 0.150114)
			(stroke
				(width 0.1)
				(type default)
			)
			(layer "B.Fab")
		)
		(pad "1" smd rect
			(at 0.2667 0 270)
			(size 0.3048 0.381)
			(layers "B.Cu" "B.Mask" "B.Paste")
			(net "P0V8_SERDES_VDDA_PEX0")
		)
		(pad "2" smd rect
			(at -0.2667 0 270)
			(size 0.3048 0.381)
			(layers "B.Cu" "B.Mask" "B.Paste")
			(net "GND")
		)
	)
	(footprint ""
		(layer "B.Cu")
		(at 289.47491 -286.399732 90)
		(property "Reference" "C3300"
			(at 0 0 90)
			(layer "B.SilkS")
			(hide yes)
			(effects
				(font
					(size 1.27 1.27)
				)
				(justify mirror)
			)
		)
		(property "Value" ""
			(at 0 0 90)
			(layer "B.Fab")
			(effects
				(font
					(size 1.27 1.27)
				)
				(justify mirror)
			)
		)
		(duplicate_pad_numbers_are_jumpers no)
		(fp_line
			(start 0.299974 -0.150114)
			(end -0.299974 -0.150114)
			(stroke
				(width 0.1)
				(type default)
			)
			(layer "B.Fab")
		)
		(fp_line
			(start -0.299974 -0.150114)
			(end -0.299974 0.150114)
			(stroke
				(width 0.1)
				(type default)
			)
			(layer "B.Fab")
		)
		(fp_line
			(start 0.299974 0.150114)
			(end 0.299974 -0.150114)
			(stroke
				(width 0.1)
				(type default)
			)
			(layer "B.Fab")
		)
		(fp_line
			(start -0.299974 0.150114)
			(end 0.299974 0.150114)
			(stroke
				(width 0.1)
				(type default)
			)
			(layer "B.Fab")
		)
		(pad "1" smd rect
			(at 0.2667 0 270)
			(size 0.3048 0.381)
			(layers "B.Cu" "B.Mask" "B.Paste")
			(net "P1V25_SERDES_VDDPLL_PEX2")
		)
		(pad "2" smd rect
			(at -0.2667 0 270)
			(size 0.3048 0.381)
			(layers "B.Cu" "B.Mask" "B.Paste")
			(net "GND")
		)
	)
	(footprint ""
		(layer "B.Cu")
		(at 110.953042 -332.70571 180)
		(property "Reference" "C2702"
			(at 0 0 0)
			(layer "B.SilkS")
			(hide yes)
			(effects
				(font
					(size 1.27 1.27)
				)
				(justify mirror)
			)
		)
		(property "Value" ""
			(at 0 0 0)
			(layer "B.Fab")
			(effects
				(font
					(size 1.27 1.27)
				)
				(justify mirror)
			)
		)
		(duplicate_pad_numbers_are_jumpers no)
		(fp_line
			(start 0.7874 0.4064)
			(end 0.7874 -0.4064)
			(stroke
				(width 0.1524)
				(type default)
			)
			(layer "B.SilkS")
		)
		(fp_line
			(start 0.7874 -0.4064)
			(end -0.7874 -0.4064)
			(stroke
				(width 0.1524)
				(type default)
			)
			(layer "B.SilkS")
		)
		(fp_line
			(start -0.7874 0.4064)
			(end 0.7874 0.4064)
			(stroke
				(width 0.1524)
				(type default)
			)
			(layer "B.SilkS")
		)
		(fp_line
			(start -0.7874 -0.4064)
			(end -0.7874 0.4064)
			(stroke
				(width 0.1524)
				(type default)
			)
			(layer "B.SilkS")
		)
		(fp_line
			(start 0.67945 0.3048)
			(end 0.67945 -0.305054)
			(stroke
				(width 0.1)
				(type default)
			)
			(layer "B.Fab")
		)
		(fp_line
			(start 0.67945 -0.305054)
			(end 0.12065 -0.305054)
			(stroke
				(width 0.1)
				(type default)
			)
			(layer "B.Fab")
		)
		(fp_line
			(start 0.12065 0.3048)
			(end 0.67945 0.3048)
			(stroke
				(width 0.1)
				(type default)
			)
			(layer "B.Fab")
		)
		(fp_line
			(start 0.12065 0.2794)
			(end 0.12065 0.3048)
			(stroke
				(width 0.1)
				(type default)
			)
			(layer "B.Fab")
		)
		(fp_line
			(start 0.12065 -0.2794)
			(end -0.12065 -0.2794)
			(stroke
				(width 0.1)
				(type default)
			)
			(layer "B.Fab")
		)
		(fp_line
			(start 0.12065 -0.305054)
			(end 0.12065 -0.2794)
			(stroke
				(width 0.1)
				(type default)
			)
			(layer "B.Fab")
		)
		(fp_line
			(start -0.120396 0.3048)
			(end -0.120396 0.2794)
			(stroke
				(width 0.1)
				(type default)
			)
			(layer "B.Fab")
		)
		(fp_line
			(start -0.120396 0.2794)
			(end 0.12065 0.2794)
			(stroke
				(width 0.1)
				(type default)
			)
			(layer "B.Fab")
		)
		(fp_line
			(start -0.12065 -0.2794)
			(end -0.12065 -0.3048)
			(stroke
				(width 0.1)
				(type default)
			)
			(layer "B.Fab")
		)
		(fp_line
			(start -0.12065 -0.3048)
			(end -0.67945 -0.3048)
			(stroke
				(width 0.1)
				(type default)
			)
			(layer "B.Fab")
		)
		(fp_line
			(start -0.67945 0.3048)
			(end -0.120396 0.3048)
			(stroke
				(width 0.1)
				(type default)
			)
			(layer "B.Fab")
		)
		(fp_line
			(start -0.67945 -0.3048)
			(end -0.67945 0.3048)
			(stroke
				(width 0.1)
				(type default)
			)
			(layer "B.Fab")
		)
		(pad "1" smd circle
			(at 0.40005 0)
			(size 0 0)
			(layers "B.Cu" "B.Mask" "B.Paste")
			(net "P3V3_CLK_BUFFER_9ZXL0451E_VZX3P3A")
		)
		(pad "2" smd circle
			(at -0.40005 0)
			(size 0 0)
			(layers "B.Cu" "B.Mask" "B.Paste")
			(net "GND")
		)
	)
	(footprint ""
		(layer "B.Cu")
		(at 292.79977 -292.099746 90)
		(property "Reference" "C1725"
			(at 0 0 90)
			(layer "B.SilkS")
			(hide yes)
			(effects
				(font
					(size 1.27 1.27)
				)
				(justify mirror)
			)
		)
		(property "Value" ""
			(at 0 0 90)
			(layer "B.Fab")
			(effects
				(font
					(size 1.27 1.27)
				)
				(justify mirror)
			)
		)
		(duplicate_pad_numbers_are_jumpers no)
		(fp_line
			(start 0.299974 -0.150114)
			(end -0.299974 -0.150114)
			(stroke
				(width 0.1)
				(type default)
			)
			(layer "B.Fab")
		)
		(fp_line
			(start -0.299974 -0.150114)
			(end -0.299974 0.150114)
			(stroke
				(width 0.1)
				(type default)
			)
			(layer "B.Fab")
		)
		(fp_line
			(start 0.299974 0.150114)
			(end 0.299974 -0.150114)
			(stroke
				(width 0.1)
				(type default)
			)
			(layer "B.Fab")
		)
		(fp_line
			(start -0.299974 0.150114)
			(end 0.299974 0.150114)
			(stroke
				(width 0.1)
				(type default)
			)
			(layer "B.Fab")
		)
		(pad "1" smd rect
			(at 0.2667 0 270)
			(size 0.3048 0.381)
			(layers "B.Cu" "B.Mask" "B.Paste")
			(net "P0V8_SERDES_VDDA_PEX2")
		)
		(pad "2" smd rect
			(at -0.2667 0 270)
			(size 0.3048 0.381)
			(layers "B.Cu" "B.Mask" "B.Paste")
			(net "GND")
		)
	)
	(footprint ""
		(layer "B.Cu")
		(at 301.607474 -223.599502 -90)
		(property "Reference" "R1868"
			(at 0 0 90)
			(layer "B.SilkS")
			(hide yes)
			(effects
				(font
					(size 1.27 1.27)
				)
				(justify mirror)
			)
		)
		(property "Value" ""
			(at 0 0 90)
			(layer "B.Fab")
			(effects
				(font
					(size 1.27 1.27)
				)
				(justify mirror)
			)
		)
		(duplicate_pad_numbers_are_jumpers no)
		(fp_line
			(start -0.7874 0.4064)
			(end 0.7874 0.4064)
			(stroke
				(width 0.1524)
				(type default)
			)
			(layer "B.SilkS")
		)
		(fp_line
			(start 0.7874 0.4064)
			(end 0.7874 -0.4064)
			(stroke
				(width 0.1524)
				(type default)
			)
			(layer "B.SilkS")
		)
		(fp_line
			(start -0.7874 -0.4064)
			(end -0.7874 0.4064)
			(stroke
				(width 0.1524)
				(type default)
			)
			(layer "B.SilkS")
		)
		(fp_line
			(start 0.7874 -0.4064)
			(end -0.7874 -0.4064)
			(stroke
				(width 0.1524)
				(type default)
			)
			(layer "B.SilkS")
		)
		(fp_line
			(start -0.67945 0.3048)
			(end -0.120396 0.3048)
			(stroke
				(width 0.1)
				(type default)
			)
			(layer "B.Fab")
		)
		(fp_line
			(start -0.120396 0.3048)
			(end -0.120396 0.2794)
			(stroke
				(width 0.1)
				(type default)
			)
			(layer "B.Fab")
		)
		(fp_line
			(start 0.12065 0.3048)
			(end 0.67945 0.3048)
			(stroke
				(width 0.1)
				(type default)
			)
			(layer "B.Fab")
		)
		(fp_line
			(start 0.67945 0.3048)
			(end 0.67945 -0.305054)
			(stroke
				(width 0.1)
				(type default)
			)
			(layer "B.Fab")
		)
		(fp_line
			(start -0.120396 0.2794)
			(end 0.12065 0.2794)
			(stroke
				(width 0.1)
				(type default)
			)
			(layer "B.Fab")
		)
		(fp_line
			(start 0.12065 0.2794)
			(end 0.12065 0.3048)
			(stroke
				(width 0.1)
				(type default)
			)
			(layer "B.Fab")
		)
		(fp_line
			(start -0.12065 -0.2794)
			(end -0.12065 -0.3048)
			(stroke
				(width 0.1)
				(type default)
			)
			(layer "B.Fab")
		)
		(fp_line
			(start 0.12065 -0.2794)
			(end -0.12065 -0.2794)
			(stroke
				(width 0.1)
				(type default)
			)
			(layer "B.Fab")
		)
		(fp_line
			(start -0.67945 -0.3048)
			(end -0.67945 0.3048)
			(stroke
				(width 0.1)
				(type default)
			)
			(layer "B.Fab")
		)
		(fp_line
			(start -0.12065 -0.3048)
			(end -0.67945 -0.3048)
			(stroke
				(width 0.1)
				(type default)
			)
			(layer "B.Fab")
		)
		(fp_line
			(start 0.12065 -0.305054)
			(end 0.12065 -0.2794)
			(stroke
				(width 0.1)
				(type default)
			)
			(layer "B.Fab")
		)
		(fp_line
			(start 0.67945 -0.305054)
			(end 0.12065 -0.305054)
			(stroke
				(width 0.1)
				(type default)
			)
			(layer "B.Fab")
		)
		(pad "1" smd circle
			(at 0.40005 0 90)
			(size 0 0)
			(layers "B.Cu" "B.Mask" "B.Paste")
			(net "RST_GPU_PERST_2_N")
		)
		(pad "2" smd circle
			(at -0.40005 0 90)
			(size 0 0)
			(layers "B.Cu" "B.Mask" "B.Paste")
			(net "RST_GPU_PERST_2_R_N")
		)
	)
	(footprint ""
		(layer "B.Cu")
		(at 217.235786 -217.286586 180)
		(property "Reference" "C3621"
			(at 0 0 0)
			(layer "B.SilkS")
			(hide yes)
			(effects
				(font
					(size 1.27 1.27)
				)
				(justify mirror)
			)
		)
		(property "Value" ""
			(at 0 0 0)
			(layer "B.Fab")
			(effects
				(font
					(size 1.27 1.27)
				)
				(justify mirror)
			)
		)
		(duplicate_pad_numbers_are_jumpers no)
		(fp_line
			(start 0.7874 0.4064)
			(end 0.7874 -0.4064)
			(stroke
				(width 0.1524)
				(type default)
			)
			(layer "B.SilkS")
		)
		(fp_line
			(start 0.7874 -0.4064)
			(end -0.7874 -0.4064)
			(stroke
				(width 0.1524)
				(type default)
			)
			(layer "B.SilkS")
		)
		(fp_line
			(start -0.7874 0.4064)
			(end 0.7874 0.4064)
			(stroke
				(width 0.1524)
				(type default)
			)
			(layer "B.SilkS")
		)
		(fp_line
			(start -0.7874 -0.4064)
			(end -0.7874 0.4064)
			(stroke
				(width 0.1524)
				(type default)
			)
			(layer "B.SilkS")
		)
		(fp_line
			(start 0.67945 0.3048)
			(end 0.67945 -0.305054)
			(stroke
				(width 0.1)
				(type default)
			)
			(layer "B.Fab")
		)
		(fp_line
			(start 0.67945 -0.305054)
			(end 0.12065 -0.305054)
			(stroke
				(width 0.1)
				(type default)
			)
			(layer "B.Fab")
		)
		(fp_line
			(start 0.12065 0.3048)
			(end 0.67945 0.3048)
			(stroke
				(width 0.1)
				(type default)
			)
			(layer "B.Fab")
		)
		(fp_line
			(start 0.12065 0.2794)
			(end 0.12065 0.3048)
			(stroke
				(width 0.1)
				(type default)
			)
			(layer "B.Fab")
		)
		(fp_line
			(start 0.12065 -0.2794)
			(end -0.12065 -0.2794)
			(stroke
				(width 0.1)
				(type default)
			)
			(layer "B.Fab")
		)
		(fp_line
			(start 0.12065 -0.305054)
			(end 0.12065 -0.2794)
			(stroke
				(width 0.1)
				(type default)
			)
			(layer "B.Fab")
		)
		(fp_line
			(start -0.120396 0.3048)
			(end -0.120396 0.2794)
			(stroke
				(width 0.1)
				(type default)
			)
			(layer "B.Fab")
		)
		(fp_line
			(start -0.120396 0.2794)
			(end 0.12065 0.2794)
			(stroke
				(width 0.1)
				(type default)
			)
			(layer "B.Fab")
		)
		(fp_line
			(start -0.12065 -0.2794)
			(end -0.12065 -0.3048)
			(stroke
				(width 0.1)
				(type default)
			)
			(layer "B.Fab")
		)
		(fp_line
			(start -0.12065 -0.3048)
			(end -0.67945 -0.3048)
			(stroke
				(width 0.1)
				(type default)
			)
			(layer "B.Fab")
		)
		(fp_line
			(start -0.67945 0.3048)
			(end -0.120396 0.3048)
			(stroke
				(width 0.1)
				(type default)
			)
			(layer "B.Fab")
		)
		(fp_line
			(start -0.67945 -0.3048)
			(end -0.67945 0.3048)
			(stroke
				(width 0.1)
				(type default)
			)
			(layer "B.Fab")
		)
		(pad "1" smd circle
			(at 0.40005 0)
			(size 0 0)
			(layers "B.Cu" "B.Mask" "B.Paste")
			(net "GND")
		)
		(pad "2" smd circle
			(at -0.40005 0)
			(size 0 0)
			(layers "B.Cu" "B.Mask" "B.Paste")
			(net "PECI_VDD")
		)
	)
	(footprint ""
		(layer "B.Cu")
		(at 45.864272 -142.795752 180)
		(property "Reference" "C847"
			(at 0 0 0)
			(layer "B.SilkS")
			(hide yes)
			(effects
				(font
					(size 1.27 1.27)
				)
				(justify mirror)
			)
		)
		(property "Value" ""
			(at 0 0 0)
			(layer "B.Fab")
			(effects
				(font
					(size 1.27 1.27)
				)
				(justify mirror)
			)
		)
		(duplicate_pad_numbers_are_jumpers no)
		(fp_line
			(start 0.299974 0.150114)
			(end 0.299974 -0.150114)
			(stroke
				(width 0.1)
				(type default)
			)
			(layer "B.Fab")
		)
		(fp_line
			(start 0.299974 -0.150114)
			(end -0.299974 -0.150114)
			(stroke
				(width 0.1)
				(type default)
			)
			(layer "B.Fab")
		)
		(fp_line
			(start -0.299974 0.150114)
			(end 0.299974 0.150114)
			(stroke
				(width 0.1)
				(type default)
			)
			(layer "B.Fab")
		)
		(fp_line
			(start -0.299974 -0.150114)
			(end -0.299974 0.150114)
			(stroke
				(width 0.1)
				(type default)
			)
			(layer "B.Fab")
		)
		(pad "1" smd rect
			(at 0.2667 0)
			(size 0.3048 0.381)
			(layers "B.Cu" "B.Mask" "B.Paste")
			(net "P12V_NIC0")
		)
		(pad "2" smd rect
			(at -0.2667 0)
			(size 0.3048 0.381)
			(layers "B.Cu" "B.Mask" "B.Paste")
			(net "GND")
		)
	)
	(footprint ""
		(layer "B.Cu")
		(at 402.249894 -292.099746 90)
		(property "Reference" "C1981"
			(at 0 0 90)
			(layer "B.SilkS")
			(hide yes)
			(effects
				(font
					(size 1.27 1.27)
				)
				(justify mirror)
			)
		)
		(property "Value" ""
			(at 0 0 90)
			(layer "B.Fab")
			(effects
				(font
					(size 1.27 1.27)
				)
				(justify mirror)
			)
		)
		(duplicate_pad_numbers_are_jumpers no)
		(fp_line
			(start 0.299974 -0.150114)
			(end -0.299974 -0.150114)
			(stroke
				(width 0.1)
				(type default)
			)
			(layer "B.Fab")
		)
		(fp_line
			(start -0.299974 -0.150114)
			(end -0.299974 0.150114)
			(stroke
				(width 0.1)
				(type default)
			)
			(layer "B.Fab")
		)
		(fp_line
			(start 0.299974 0.150114)
			(end 0.299974 -0.150114)
			(stroke
				(width 0.1)
				(type default)
			)
			(layer "B.Fab")
		)
		(fp_line
			(start -0.299974 0.150114)
			(end 0.299974 0.150114)
			(stroke
				(width 0.1)
				(type default)
			)
			(layer "B.Fab")
		)
		(pad "1" smd rect
			(at 0.2667 0 270)
			(size 0.3048 0.381)
			(layers "B.Cu" "B.Mask" "B.Paste")
			(net "P0V8_SERDES_VDDA_PEX3")
		)
		(pad "2" smd rect
			(at -0.2667 0 270)
			(size 0.3048 0.381)
			(layers "B.Cu" "B.Mask" "B.Paste")
			(net "GND")
		)
	)
)
